# T6G (Grand Teton) — schematic netlist excerpt (pin names and nets, part order shuffled) for the footprints in the layout excerpt that follows; sources: Cadence DE-HDL packaged netlist, KiCad conversion of 04192023_DAF0TMB3IC0_F0TG_MB_C_brd_V02_OCP.brd

C1877  Q_CAP  0.1UF 25V 10% X7R  pkg 0402  page 143 : A = P3V3_AUX ; B = GND
PR214  Q_RES  8.87K 1% EMPTY  pkg 0402LF  page 216 : A = GND ; B = PVDDCR_SOC_P1_LSET3

(kicad_pcb
	(version 20260206)
	(generator "pcbnew")
	(generator_version "10.0")
	(general
		(thickness 1.6)
		(legacy_teardrops no)
	)
	(paper "A4")
	(title_block
		(title "04192023_DAF0TMB3IC0_F0TG_MB_C_brd_V02_OCP.brd")
		(comment 1 "Grand Teton / footprints 3342-3343 of 8354")
	)
	(layers
		(0 "F.Cu" signal "TOP")
		(4 "In1.Cu" signal "GND")
		(6 "In2.Cu" signal "IN1")
		(8 "In3.Cu" signal "GND1")
		(10 "In4.Cu" signal "IN2")
		(12 "In5.Cu" signal "GND2")
		(14 "In6.Cu" signal "IN3")
		(16 "In7.Cu" signal "GND3")
		(18 "In8.Cu" signal "VCC")
		(20 "In9.Cu" signal "VCC1")
		(22 "In10.Cu" signal "GND4")
		(24 "In11.Cu" signal "IN4")
		(26 "In12.Cu" signal "GND5")
		(28 "In13.Cu" signal "IN5")
		(30 "In14.Cu" signal "GND6")
		(32 "In15.Cu" signal "IN6")
		(34 "In16.Cu" signal "GND7")
		(2 "B.Cu" signal "BOTTOM")
		(9 "F.Adhes" user "F.Adhesive")
		(11 "B.Adhes" user "B.Adhesive")
		(13 "F.Paste" user "Package Geometry/Pastemask Top")
		(15 "B.Paste" user "Package Geometry/Pastemask Bottom")
		(5 "F.SilkS" user "Ref Des/Silkscreen Top")
		(7 "B.SilkS" user "Ref Des/Silkscreen Bottom")
		(1 "F.Mask" user "Board Geometry/Soldermask Top")
		(3 "B.Mask" user "Board Geometry/Soldermask Bottom")
		(17 "Dwgs.User" user "User.Drawings")
		(19 "Cmts.User" user "User.Comments")
		(21 "Eco1.User" user "User.Eco1")
		(23 "Eco2.User" user "User.Eco2")
		(25 "Edge.Cuts" user "Board Geometry/Outline")
		(27 "Margin" user)
		(31 "F.CrtYd" user "Package Geometry/Place Bound Top")
		(29 "B.CrtYd" user "Package Geometry/Place Bound Bottom")
		(35 "F.Fab" user "Ref Des/Assembly Top")
		(33 "B.Fab" user "Ref Des/Assembly Bottom")
	)
	(footprint ""
		(layer "F.Cu")
		(at 156.30779 -98.755708 90)
		(property "Reference" "C1877"
			(at 0 0 90)
			(layer "F.SilkS")
			(hide yes)
			(effects
				(font
					(size 1.27 1.27)
				)
			)
		)
		(property "Value" ""
			(at 0 0 90)
			(layer "F.Fab")
			(effects
				(font
					(size 1.27 1.27)
				)
			)
		)
		(duplicate_pad_numbers_are_jumpers no)
		(fp_line
			(start 0.7874 -0.4064)
			(end 0.7874 0.4064)
			(stroke
				(width 0.1524)
				(type default)
			)
			(layer "F.SilkS")
		)
		(fp_line
			(start -0.7874 -0.4064)
			(end 0.7874 -0.4064)
			(stroke
				(width 0.1524)
				(type default)
			)
			(layer "F.SilkS")
		)
		(fp_line
			(start 0.7874 0.4064)
			(end -0.7874 0.4064)
			(stroke
				(width 0.1524)
				(type default)
			)
			(layer "F.SilkS")
		)
		(fp_line
			(start -0.7874 0.4064)
			(end -0.7874 -0.4064)
			(stroke
				(width 0.1524)
				(type default)
			)
			(layer "F.SilkS")
		)
		(fp_line
			(start -0.12065 -0.305054)
			(end -0.12065 -0.2794)
			(stroke
				(width 0.1)
				(type default)
			)
			(layer "F.Fab")
		)
		(fp_line
			(start -0.67945 -0.305054)
			(end -0.12065 -0.305054)
			(stroke
				(width 0.1)
				(type default)
			)
			(layer "F.Fab")
		)
		(fp_line
			(start 0.67945 -0.3048)
			(end 0.67945 0.3048)
			(stroke
				(width 0.1)
				(type default)
			)
			(layer "F.Fab")
		)
		(fp_line
			(start 0.12065 -0.3048)
			(end 0.67945 -0.3048)
			(stroke
				(width 0.1)
				(type default)
			)
			(layer "F.Fab")
		)
		(fp_line
			(start 0.12065 -0.2794)
			(end 0.12065 -0.3048)
			(stroke
				(width 0.1)
				(type default)
			)
			(layer "F.Fab")
		)
		(fp_line
			(start -0.12065 -0.2794)
			(end 0.12065 -0.2794)
			(stroke
				(width 0.1)
				(type default)
			)
			(layer "F.Fab")
		)
		(fp_line
			(start 0.120396 0.2794)
			(end -0.12065 0.2794)
			(stroke
				(width 0.1)
				(type default)
			)
			(layer "F.Fab")
		)
		(fp_line
			(start -0.12065 0.2794)
			(end -0.12065 0.3048)
			(stroke
				(width 0.1)
				(type default)
			)
			(layer "F.Fab")
		)
		(fp_line
			(start 0.67945 0.3048)
			(end 0.120396 0.3048)
			(stroke
				(width 0.1)
				(type default)
			)
			(layer "F.Fab")
		)
		(fp_line
			(start 0.120396 0.3048)
			(end 0.120396 0.2794)
			(stroke
				(width 0.1)
				(type default)
			)
			(layer "F.Fab")
		)
		(fp_line
			(start -0.12065 0.3048)
			(end -0.67945 0.3048)
			(stroke
				(width 0.1)
				(type default)
			)
			(layer "F.Fab")
		)
		(fp_line
			(start -0.67945 0.3048)
			(end -0.67945 -0.305054)
			(stroke
				(width 0.1)
				(type default)
			)
			(layer "F.Fab")
		)
		(pad "1" smd circle
			(at -0.40005 0 90)
			(size 0 0)
			(layers "F.Cu" "F.Mask" "F.Paste")
			(net "P3V3_AUX")
		)
		(pad "2" smd circle
			(at 0.40005 0 90)
			(size 0 0)
			(layers "F.Cu" "F.Mask" "F.Paste")
			(net "GND")
		)
	)
	(footprint ""
		(layer "F.Cu")
		(at 133.728714 -151.319484)
		(property "Reference" "PR214"
			(at 0 0 0)
			(layer "F.SilkS")
			(hide yes)
			(effects
				(font
					(size 1.27 1.27)
				)
			)
		)
		(property "Value" ""
			(at 0 0 0)
			(layer "F.Fab")
			(effects
				(font
					(size 1.27 1.27)
				)
			)
		)
		(duplicate_pad_numbers_are_jumpers no)
		(fp_line
			(start -0.7874 -0.4064)
			(end 0.7874 -0.4064)
			(stroke
				(width 0.1524)
				(type default)
			)
			(layer "F.SilkS")
		)
		(fp_line
			(start -0.7874 0.4064)
			(end -0.7874 -0.4064)
			(stroke
				(width 0.1524)
				(type default)
			)
			(layer "F.SilkS")
		)
		(fp_line
			(start 0.7874 -0.4064)
			(end 0.7874 0.4064)
			(stroke
				(width 0.1524)
				(type default)
			)
			(layer "F.SilkS")
		)
		(fp_line
			(start 0.7874 0.4064)
			(end -0.7874 0.4064)
			(stroke
				(width 0.1524)
				(type default)
			)
			(layer "F.SilkS")
		)
		(fp_line
			(start -0.67945 -0.305054)
			(end -0.12065 -0.305054)
			(stroke
				(width 0.1)
				(type default)
			)
			(layer "F.Fab")
		)
		(fp_line
			(start -0.67945 0.3048)
			(end -0.67945 -0.305054)
			(stroke
				(width 0.1)
				(type default)
			)
			(layer "F.Fab")
		)
		(fp_line
			(start -0.12065 -0.305054)
			(end -0.12065 -0.2794)
			(stroke
				(width 0.1)
				(type default)
			)
			(layer "F.Fab")
		)
		(fp_line
			(start -0.12065 -0.2794)
			(end 0.12065 -0.2794)
			(stroke
				(width 0.1)
				(type default)
			)
			(layer "F.Fab")
		)
		(fp_line
			(start -0.12065 0.2794)
			(end -0.12065 0.3048)
			(stroke
				(width 0.1)
				(type default)
			)
			(layer "F.Fab")
		)
		(fp_line
			(start -0.12065 0.3048)
			(end -0.67945 0.3048)
			(stroke
				(width 0.1)
				(type default)
			)
			(layer "F.Fab")
		)
		(fp_line
			(start 0.120396 0.2794)
			(end -0.12065 0.2794)
			(stroke
				(width 0.1)
				(type default)
			)
			(layer "F.Fab")
		)
		(fp_line
			(start 0.120396 0.3048)
			(end 0.120396 0.2794)
			(stroke
				(width 0.1)
				(type default)
			)
			(layer "F.Fab")
		)
		(fp_line
			(start 0.12065 -0.3048)
			(end 0.67945 -0.3048)
			(stroke
				(width 0.1)
				(type default)
			)
			(layer "F.Fab")
		)
		(fp_line
			(start 0.12065 -0.2794)
			(end 0.12065 -0.3048)
			(stroke
				(width 0.1)
				(type default)
			)
			(layer "F.Fab")
		)
		(fp_line
			(start 0.67945 -0.3048)
			(end 0.67945 0.3048)
			(stroke
				(width 0.1)
				(type default)
			)
			(layer "F.Fab")
		)
		(fp_line
			(start 0.67945 0.3048)
			(end 0.120396 0.3048)
			(stroke
				(width 0.1)
				(type default)
			)
			(layer "F.Fab")
		)
		(pad "1" smd circle
			(at -0.40005 0)
			(size 0 0)
			(layers "F.Cu" "F.Mask" "F.Paste")
			(net "GND")
		)
		(pad "2" smd circle
			(at 0.40005 0)
			(size 0 0)
			(layers "F.Cu" "F.Mask" "F.Paste")
			(net "PVDDCR_SOC_P1_LSET3")
		)
	)
)
